(kicad_pcb
	(version 20260206)
	(generator "pcbnew")
	(generator_version "10.0")
	(general
		(thickness 1.6)
		(legacy_teardrops no)
	)
	(paper "A4")
	(title_block
		(title "Wiwynn_Tioga_Pass_MB.brd")
		(comment 1 "Tioga Pass / footprints 2119-2125 of 4770")
	)
	(layers
		(0 "F.Cu" signal "TOP")
		(4 "In1.Cu" signal "L2GND")
		(6 "In2.Cu" signal "L3")
		(8 "In3.Cu" signal "L4GND")
		(10 "In4.Cu" signal "L5")
		(12 "In5.Cu" signal "L6GND")
		(14 "In6.Cu" signal "L7VCC")
		(16 "In7.Cu" signal "L8VCC")
		(18 "In8.Cu" signal "L9GND")
		(20 "In9.Cu" signal "L10")
		(22 "In10.Cu" signal "L11GND")
		(24 "In11.Cu" signal "L12")
		(26 "In12.Cu" signal "L13GND")
		(2 "B.Cu" signal "BOTTOM")
		(9 "F.Adhes" user "F.Adhesive")
		(11 "B.Adhes" user "B.Adhesive")
		(13 "F.Paste" user "Package Geometry/Pastemask Top")
		(15 "B.Paste" user "Package Geometry/Pastemask Bottom")
		(5 "F.SilkS" user "Ref Des/Silkscreen Top")
		(7 "B.SilkS" user "Ref Des/Silkscreen Bottom")
		(1 "F.Mask" user "Board Geometry/Soldermask Top")
		(3 "B.Mask" user "Board Geometry/Soldermask Bottom")
		(17 "Dwgs.User" user "User.Drawings")
		(19 "Cmts.User" user "User.Comments")
		(21 "Eco1.User" user "User.Eco1")
		(23 "Eco2.User" user "User.Eco2")
		(25 "Edge.Cuts" user "Board Geometry/Outline")
		(27 "Margin" user)
		(31 "F.CrtYd" user "Package Geometry/Place Bound Top")
		(29 "B.CrtYd" user "Package Geometry/Place Bound Bottom")
		(35 "F.Fab" user "Ref Des/Assembly Top")
		(33 "B.Fab" user "Ref Des/Assembly Bottom")
	)
	(footprint ""
		(layer "F.Cu")
		(at 180.975 -5.334)
		(property "Reference" "R4G18"
			(at 0 0 0)
			(layer "F.SilkS")
			(hide yes)
			(effects
				(font
					(size 1.27 1.27)
				)
			)
		)
		(property "Value" ""
			(at 0 0 0)
			(layer "F.Fab")
			(effects
				(font
					(size 1.27 1.27)
				)
			)
		)
		(duplicate_pad_numbers_are_jumpers no)
		(fp_rect
			(start 0.2794 0.9906)
			(end -0.2794 -0.1016)
			(stroke
				(width 0)
				(type default)
			)
			(fill no)
			(layer "F.CrtYd")
		)
		(fp_line
			(start -0.2794 -0.1016)
			(end -0.2794 0.9906)
			(stroke
				(width 0.1)
				(type default)
			)
			(layer "F.Fab")
		)
		(fp_line
			(start -0.2794 0.9906)
			(end 0.2794 0.9906)
			(stroke
				(width 0.1)
				(type default)
			)
			(layer "F.Fab")
		)
		(fp_line
			(start 0.2794 -0.1016)
			(end -0.2794 -0.1016)
			(stroke
				(width 0.1)
				(type default)
			)
			(layer "F.Fab")
		)
		(fp_line
			(start 0.2794 0.9906)
			(end 0.2794 -0.1016)
			(stroke
				(width 0.1)
				(type default)
			)
			(layer "F.Fab")
		)
		(pad "1" smd rect
			(at 0 0)
			(size 0.508 0.508)
			(layers "F.Cu" "F.Mask" "F.Paste")
			(net "P3V3")
		)
		(pad "2" smd rect
			(at 0 0.889)
			(size 0.508 0.508)
			(layers "F.Cu" "F.Mask" "F.Paste")
			(net "PWRGD_PVTT_ABC_CPU0_R")
		)
		(zone
			(layer "F.Cu")
			(hatch none 0.5)
			(connect_pads
				(clearance 0)
			)
			(min_thickness 0.25)
			(keepout
				(tracks not_allowed)
				(vias allowed)
				(pads allowed)
				(copperpour not_allowed)
				(footprints allowed)
			)
			(placement
				(enabled no)
				(sheetname "")
			)
			(fill
				(thermal_gap 0.5)
				(thermal_bridge_width 0.5)
				(island_removal_mode 0)
			)
			(polygon
				(pts
					(xy 181.229 -4.699) (xy 181.229 -5.08) (xy 180.721 -5.08) (xy 180.721 -4.699)
				)
			)
		)
		(zone
			(layer "F.Cu")
			(hatch none 0.5)
			(connect_pads
				(clearance 0)
			)
			(min_thickness 0.25)
			(keepout
				(tracks allowed)
				(vias not_allowed)
				(pads allowed)
				(copperpour not_allowed)
				(footprints allowed)
			)
			(placement
				(enabled no)
				(sheetname "")
			)
			(fill
				(thermal_gap 0.5)
				(thermal_bridge_width 0.5)
				(island_removal_mode 0)
			)
			(polygon
				(pts
					(xy 181.229 -4.699) (xy 181.229 -5.08) (xy 180.721 -5.08) (xy 180.721 -4.699)
				)
			)
		)
	)
	(footprint ""
		(layer "F.Cu")
		(at 378.46 -87.3125 180)
		(property "Reference" "R7D2"
			(at 0 0 180)
			(layer "F.SilkS")
			(hide yes)
			(effects
				(font
					(size 1.27 1.27)
				)
			)
		)
		(property "Value" ""
			(at 0 0 180)
			(layer "F.Fab")
			(effects
				(font
					(size 1.27 1.27)
				)
			)
		)
		(duplicate_pad_numbers_are_jumpers no)
		(fp_poly
			(pts
				(xy -0.2794 -0.1016) (xy 0.2794 -0.1016) (xy 0.2794 0.9906) (xy -0.2794 0.9906)
			)
			(stroke
				(width 0)
				(type default)
			)
			(fill no)
			(layer "F.CrtYd")
		)
		(fp_line
			(start 0.2794 0.9906)
			(end 0.2794 -0.1016)
			(stroke
				(width 0.1)
				(type default)
			)
			(layer "F.Fab")
		)
		(fp_line
			(start 0.2794 -0.1016)
			(end -0.2794 -0.1016)
			(stroke
				(width 0.1)
				(type default)
			)
			(layer "F.Fab")
		)
		(fp_line
			(start -0.2794 0.9906)
			(end 0.2794 0.9906)
			(stroke
				(width 0.1)
				(type default)
			)
			(layer "F.Fab")
		)
		(fp_line
			(start -0.2794 -0.1016)
			(end -0.2794 0.9906)
			(stroke
				(width 0.1)
				(type default)
			)
			(layer "F.Fab")
		)
		(pad "1" smd rect
			(at 0 0 180)
			(size 0.508 0.508)
			(layers "F.Cu" "F.Mask" "F.Paste")
			(net "P3V3_STBY")
		)
		(pad "2" smd rect
			(at 0 0.889 180)
			(size 0.508 0.508)
			(layers "F.Cu" "F.Mask" "F.Paste")
			(net "PU_FM_RCIN_N")
		)
		(zone
			(layer "F.Cu")
			(hatch none 0.5)
			(connect_pads
				(clearance 0)
			)
			(min_thickness 0.25)
			(keepout
				(tracks not_allowed)
				(vias allowed)
				(pads allowed)
				(copperpour not_allowed)
				(footprints allowed)
			)
			(placement
				(enabled no)
				(sheetname "")
			)
			(fill
				(thermal_gap 0.5)
				(thermal_bridge_width 0.5)
				(island_removal_mode 0)
			)
			(polygon
				(pts
					(xy 378.714 -87.9475) (xy 378.206 -87.9475) (xy 378.206 -87.5665) (xy 378.714 -87.5665)
				)
			)
		)
		(zone
			(layer "F.Cu")
			(hatch none 0.5)
			(connect_pads
				(clearance 0)
			)
			(min_thickness 0.25)
			(keepout
				(tracks allowed)
				(vias not_allowed)
				(pads allowed)
				(copperpour not_allowed)
				(footprints allowed)
			)
			(placement
				(enabled no)
				(sheetname "")
			)
			(fill
				(thermal_gap 0.5)
				(thermal_bridge_width 0.5)
				(island_removal_mode 0)
			)
			(polygon
				(pts
					(xy 378.714 -87.5665) (xy 378.206 -87.5665) (xy 378.206 -87.9475) (xy 378.714 -87.9475)
				)
			)
		)
	)
	(footprint ""
		(layer "F.Cu")
		(at 409.1305 -50.038 90)
		(property "Reference" "R8D28"
			(at 0 0 90)
			(layer "F.SilkS")
			(hide yes)
			(effects
				(font
					(size 1.27 1.27)
				)
			)
		)
		(property "Value" ""
			(at 0 0 90)
			(layer "F.Fab")
			(effects
				(font
					(size 1.27 1.27)
				)
			)
		)
		(duplicate_pad_numbers_are_jumpers no)
		(fp_poly
			(pts
				(xy -0.2794 -0.1016) (xy 0.2794 -0.1016) (xy 0.2794 0.9906) (xy -0.2794 0.9906)
			)
			(stroke
				(width 0)
				(type default)
			)
			(fill no)
			(layer "F.CrtYd")
		)
		(fp_line
			(start 0.2794 -0.1016)
			(end -0.2794 -0.1016)
			(stroke
				(width 0.1)
				(type default)
			)
			(layer "F.Fab")
		)
		(fp_line
			(start -0.2794 -0.1016)
			(end -0.2794 0.9906)
			(stroke
				(width 0.1)
				(type default)
			)
			(layer "F.Fab")
		)
		(fp_line
			(start 0.2794 0.9906)
			(end 0.2794 -0.1016)
			(stroke
				(width 0.1)
				(type default)
			)
			(layer "F.Fab")
		)
		(fp_line
			(start -0.2794 0.9906)
			(end 0.2794 0.9906)
			(stroke
				(width 0.1)
				(type default)
			)
			(layer "F.Fab")
		)
		(pad "1" smd rect
			(at 0 0 90)
			(size 0.508 0.508)
			(layers "F.Cu" "F.Mask" "F.Paste")
			(net "P3V3_STBY")
		)
		(pad "2" smd rect
			(at 0 0.889 90)
			(size 0.508 0.508)
			(layers "F.Cu" "F.Mask" "F.Paste")
			(net "PU_AT24C64_A2")
		)
		(zone
			(layer "F.Cu")
			(hatch none 0.5)
			(connect_pads
				(clearance 0)
			)
			(min_thickness 0.25)
			(keepout
				(tracks allowed)
				(vias not_allowed)
				(pads allowed)
				(copperpour not_allowed)
				(footprints allowed)
			)
			(placement
				(enabled no)
				(sheetname "")
			)
			(fill
				(thermal_gap 0.5)
				(thermal_bridge_width 0.5)
				(island_removal_mode 0)
			)
			(polygon
				(pts
					(xy 409.3845 -49.784) (xy 409.3845 -50.292) (xy 409.7655 -50.292) (xy 409.7655 -49.784)
				)
			)
		)
		(zone
			(layer "F.Cu")
			(hatch none 0.5)
			(connect_pads
				(clearance 0)
			)
			(min_thickness 0.25)
			(keepout
				(tracks not_allowed)
				(vias allowed)
				(pads allowed)
				(copperpour not_allowed)
				(footprints allowed)
			)
			(placement
				(enabled no)
				(sheetname "")
			)
			(fill
				(thermal_gap 0.5)
				(thermal_bridge_width 0.5)
				(island_removal_mode 0)
			)
			(polygon
				(pts
					(xy 409.7655 -49.784) (xy 409.7655 -50.292) (xy 409.3845 -50.292) (xy 409.3845 -49.784)
				)
			)
		)
	)
	(footprint ""
		(layer "F.Cu")
		(at 458.177392 -38.591998 90)
		(property "Reference" "R9F8"
			(at 0 0 90)
			(layer "F.SilkS")
			(hide yes)
			(effects
				(font
					(size 1.27 1.27)
				)
			)
		)
		(property "Value" ""
			(at 0 0 90)
			(layer "F.Fab")
			(effects
				(font
					(size 1.27 1.27)
				)
			)
		)
		(duplicate_pad_numbers_are_jumpers no)
		(fp_poly
			(pts
				(xy -0.2794 -0.1016) (xy 0.2794 -0.1016) (xy 0.2794 0.9906) (xy -0.2794 0.9906)
			)
			(stroke
				(width 0)
				(type default)
			)
			(fill no)
			(layer "F.CrtYd")
		)
		(fp_line
			(start 0.2794 -0.1016)
			(end -0.2794 -0.1016)
			(stroke
				(width 0.1)
				(type default)
			)
			(layer "F.Fab")
		)
		(fp_line
			(start -0.2794 -0.1016)
			(end -0.2794 0.9906)
			(stroke
				(width 0.1)
				(type default)
			)
			(layer "F.Fab")
		)
		(fp_line
			(start 0.2794 0.9906)
			(end 0.2794 -0.1016)
			(stroke
				(width 0.1)
				(type default)
			)
			(layer "F.Fab")
		)
		(fp_line
			(start -0.2794 0.9906)
			(end 0.2794 0.9906)
			(stroke
				(width 0.1)
				(type default)
			)
			(layer "F.Fab")
		)
		(pad "1" smd rect
			(at 0 0 90)
			(size 0.508 0.508)
			(layers "F.Cu" "F.Mask" "F.Paste")
			(net "GND")
		)
		(pad "2" smd rect
			(at 0 0.889 90)
			(size 0.508 0.508)
			(layers "F.Cu" "F.Mask" "F.Paste")
			(net "VR_P1V15_BMC_STBY_FB")
		)
		(zone
			(layer "F.Cu")
			(hatch none 0.5)
			(connect_pads
				(clearance 0)
			)
			(min_thickness 0.25)
			(keepout
				(tracks allowed)
				(vias not_allowed)
				(pads allowed)
				(copperpour not_allowed)
				(footprints allowed)
			)
			(placement
				(enabled no)
				(sheetname "")
			)
			(fill
				(thermal_gap 0.5)
				(thermal_bridge_width 0.5)
				(island_removal_mode 0)
			)
			(polygon
				(pts
					(xy 458.431392 -38.337998) (xy 458.431392 -38.845998) (xy 458.812392 -38.845998) (xy 458.812392 -38.337998)
				)
			)
		)
		(zone
			(layer "F.Cu")
			(hatch none 0.5)
			(connect_pads
				(clearance 0)
			)
			(min_thickness 0.25)
			(keepout
				(tracks not_allowed)
				(vias allowed)
				(pads allowed)
				(copperpour not_allowed)
				(footprints allowed)
			)
			(placement
				(enabled no)
				(sheetname "")
			)
			(fill
				(thermal_gap 0.5)
				(thermal_bridge_width 0.5)
				(island_removal_mode 0)
			)
			(polygon
				(pts
					(xy 458.812392 -38.337998) (xy 458.812392 -38.845998) (xy 458.431392 -38.845998) (xy 458.431392 -38.337998)
				)
			)
		)
	)
	(footprint ""
		(layer "F.Cu")
		(at 330.962 -148.463 180)
		(property "Reference" "C6A4"
			(at 0 0 180)
			(layer "F.SilkS")
			(hide yes)
			(effects
				(font
					(size 1.27 1.27)
				)
			)
		)
		(property "Value" ""
			(at 0 0 180)
			(layer "F.Fab")
			(effects
				(font
					(size 1.27 1.27)
				)
			)
		)
		(duplicate_pad_numbers_are_jumpers no)
		(fp_rect
			(start -0.7239 1.9939)
			(end 0.7239 -0.2159)
			(stroke
				(width 0)
				(type default)
			)
			(fill no)
			(layer "F.CrtYd")
		)
		(fp_line
			(start 0.7239 1.9939)
			(end 0.7239 -0.2159)
			(stroke
				(width 0.1)
				(type default)
			)
			(layer "F.Fab")
		)
		(fp_line
			(start 0.7239 -0.2159)
			(end -0.7239 -0.2159)
			(stroke
				(width 0.1)
				(type default)
			)
			(layer "F.Fab")
		)
		(fp_line
			(start -0.7239 1.9939)
			(end 0.7239 1.9939)
			(stroke
				(width 0.1)
				(type default)
			)
			(layer "F.Fab")
		)
		(fp_line
			(start -0.7239 -0.2159)
			(end -0.7239 1.9939)
			(stroke
				(width 0.1)
				(type default)
			)
			(layer "F.Fab")
		)
		(pad "1" smd rect
			(at 0 0 180)
			(size 1.27 1.016)
			(layers "F.Cu" "F.Mask" "F.Paste")
			(net "PVDDQ_DEF")
		)
		(pad "2" smd rect
			(at 0 1.778 180)
			(size 1.27 1.016)
			(layers "F.Cu" "F.Mask" "F.Paste")
			(net "GND")
		)
		(zone
			(layer "F.Cu")
			(hatch none 0.5)
			(connect_pads
				(clearance 0)
			)
			(min_thickness 0.25)
			(keepout
				(tracks not_allowed)
				(vias allowed)
				(pads allowed)
				(copperpour not_allowed)
				(footprints allowed)
			)
			(placement
				(enabled no)
				(sheetname "")
			)
			(fill
				(thermal_gap 0.5)
				(thermal_bridge_width 0.5)
				(island_removal_mode 0)
			)
			(polygon
				(pts
					(xy 331.597 -149.733) (xy 330.327 -149.733) (xy 330.327 -148.971) (xy 331.597 -148.971)
				)
			)
		)
	)
	(footprint ""
		(layer "F.Cu")
		(at 49.4284 -78.359)
		(property "Reference" "C1D14"
			(at 0 0 0)
			(layer "F.SilkS")
			(hide yes)
			(effects
				(font
					(size 1.27 1.27)
				)
			)
		)
		(property "Value" ""
			(at 0 0 0)
			(layer "F.Fab")
			(effects
				(font
					(size 1.27 1.27)
				)
			)
		)
		(duplicate_pad_numbers_are_jumpers no)
		(fp_poly
			(pts
				(xy -0.4953 -0.2032) (xy 0.4953 -0.2032) (xy 0.4953 1.6002) (xy -0.4953 1.6002)
			)
			(stroke
				(width 0)
				(type default)
			)
			(fill no)
			(layer "F.CrtYd")
		)
		(fp_line
			(start -0.4953 -0.2032)
			(end 0.4953 -0.2032)
			(stroke
				(width 0.1)
				(type default)
			)
			(layer "F.Fab")
		)
		(fp_line
			(start -0.4953 1.6002)
			(end -0.4953 -0.2032)
			(stroke
				(width 0.1)
				(type default)
			)
			(layer "F.Fab")
		)
		(fp_line
			(start 0.4953 -0.2032)
			(end 0.4953 1.6002)
			(stroke
				(width 0.1)
				(type default)
			)
			(layer "F.Fab")
		)
		(fp_line
			(start 0.4953 1.6002)
			(end -0.4953 1.6002)
			(stroke
				(width 0.1)
				(type default)
			)
			(layer "F.Fab")
		)
		(pad "1" smd rect
			(at 0 0)
			(size 0.762 0.889)
			(layers "F.Cu" "F.Mask" "F.Paste")
			(net "PVCCIN_CPU1")
		)
		(pad "2" smd rect
			(at 0 1.397)
			(size 0.762 0.889)
			(layers "F.Cu" "F.Mask" "F.Paste")
			(net "GND")
		)
		(zone
			(layer "F.Cu")
			(hatch none 0.5)
			(connect_pads
				(clearance 0)
			)
			(min_thickness 0.25)
			(keepout
				(tracks not_allowed)
				(vias allowed)
				(pads allowed)
				(copperpour not_allowed)
				(footprints allowed)
			)
			(placement
				(enabled no)
				(sheetname "")
			)
			(fill
				(thermal_gap 0.5)
				(thermal_bridge_width 0.5)
				(island_removal_mode 0)
			)
			(polygon
				(pts
					(xy 49.0474 -77.9145) (xy 49.8094 -77.9145) (xy 49.8094 -77.4065) (xy 49.0474 -77.4065)
				)
			)
		)
	)
	(footprint ""
		(layer "F.Cu")
		(at 495.22126 -25.83942 -90)
		(property "Reference" "C8E19"
			(at 0 0 270)
			(layer "F.SilkS")
			(hide yes)
			(effects
				(font
					(size 1.27 1.27)
				)
			)
		)
		(property "Value" ""
			(at 0 0 270)
			(layer "F.Fab")
			(effects
				(font
					(size 1.27 1.27)
				)
			)
		)
		(duplicate_pad_numbers_are_jumpers no)
		(fp_rect
			(start 0.3048 0.9906)
			(end -0.3048 -0.1016)
			(stroke
				(width 0)
				(type default)
			)
			(fill no)
			(layer "F.CrtYd")
		)
		(fp_line
			(start -0.3048 0.9906)
			(end 0.3048 0.9906)
			(stroke
				(width 0.1)
				(type default)
			)
			(layer "F.Fab")
		)
		(fp_line
			(start 0.3048 0.9906)
			(end 0.3048 -0.1016)
			(stroke
				(width 0.1)
				(type default)
			)
			(layer "F.Fab")
		)
		(fp_line
			(start -0.3048 -0.1016)
			(end -0.3048 0.9906)
			(stroke
				(width 0.1)
				(type default)
			)
			(layer "F.Fab")
		)
		(fp_line
			(start 0.3048 -0.1016)
			(end -0.3048 -0.1016)
			(stroke
				(width 0.1)
				(type default)
			)
			(layer "F.Fab")
		)
		(pad "1" smd rect
			(at 0 0 270)
			(size 0.508 0.508)
			(layers "F.Cu" "F.Mask" "F.Paste")
			(net "P5V_STBY")
		)
		(pad "2" smd rect
			(at 0 0.889 270)
			(size 0.508 0.508)
			(layers "F.Cu" "F.Mask" "F.Paste")
			(net "GND")
		)
		(zone
			(layer "F.Cu")
			(hatch none 0.5)
			(connect_pads
				(clearance 0)
			)
			(min_thickness 0.25)
			(keepout
				(tracks allowed)
				(vias not_allowed)
				(pads allowed)
				(copperpour not_allowed)
				(footprints allowed)
			)
			(placement
				(enabled no)
				(sheetname "")
			)
			(fill
				(thermal_gap 0.5)
				(thermal_bridge_width 0.5)
				(island_removal_mode 0)
			)
			(polygon
				(pts
					(xy 494.58626 -25.58542) (xy 494.96726 -25.58542) (xy 494.96726 -26.09342) (xy 494.58626 -26.09342)
				)
			)
		)
		(zone
			(layer "F.Cu")
			(hatch none 0.5)
			(connect_pads
				(clearance 0)
			)
			(min_thickness 0.25)
			(keepout
				(tracks not_allowed)
				(vias allowed)
				(pads allowed)
				(copperpour not_allowed)
				(footprints allowed)
			)
			(placement
				(enabled no)
				(sheetname "")
			)
			(fill
				(thermal_gap 0.5)
				(thermal_bridge_width 0.5)
				(island_removal_mode 0)
			)
			(polygon
				(pts
					(xy 494.58626 -25.58542) (xy 494.96726 -25.58542) (xy 494.96726 -26.09342) (xy 494.58626 -26.09342)
				)
			)
		)
	)
)
